# BASEBOARD_FAB2 (Tioga Pass) — schematic netlist excerpt (pin names and nets, part order shuffled) for the footprints in the layout excerpt that follows; sources: Cadence DE-HDL packaged netlist, KiCad conversion of Wiwynn_Tioga_Pass_MB.brd

C6W13  CAP  100UF 4V 20% X5R  pkg 0805  page 230 : A = PVTT_KLM ; B = GND
R2N32  RES  4.75K 1% CHIP  pkg 0402  page 133 : A = P3V3_STBY ; B = FM_BIOS_SMI_ACTIVE_N
C8L5  CAP_A  47UF 4V 20% X5R  pkg 0603V  page 228 : A = PVDDQ_KLM ; B = GND

(kicad_pcb
	(version 20260206)
	(generator "pcbnew")
	(generator_version "10.0")
	(general
		(thickness 1.6)
		(legacy_teardrops no)
	)
	(paper "A4")
	(title_block
		(title "Wiwynn_Tioga_Pass_MB.brd")
		(comment 1 "Tioga Pass / footprints 3366-3368 of 4770")
	)
	(layers
		(0 "F.Cu" signal "TOP")
		(4 "In1.Cu" signal "L2GND")
		(6 "In2.Cu" signal "L3")
		(8 "In3.Cu" signal "L4GND")
		(10 "In4.Cu" signal "L5")
		(12 "In5.Cu" signal "L6GND")
		(14 "In6.Cu" signal "L7VCC")
		(16 "In7.Cu" signal "L8VCC")
		(18 "In8.Cu" signal "L9GND")
		(20 "In9.Cu" signal "L10")
		(22 "In10.Cu" signal "L11GND")
		(24 "In11.Cu" signal "L12")
		(26 "In12.Cu" signal "L13GND")
		(2 "B.Cu" signal "BOTTOM")
		(9 "F.Adhes" user "F.Adhesive")
		(11 "B.Adhes" user "B.Adhesive")
		(13 "F.Paste" user "Package Geometry/Pastemask Top")
		(15 "B.Paste" user "Package Geometry/Pastemask Bottom")
		(5 "F.SilkS" user "Ref Des/Silkscreen Top")
		(7 "B.SilkS" user "Ref Des/Silkscreen Bottom")
		(1 "F.Mask" user "Board Geometry/Soldermask Top")
		(3 "B.Mask" user "Board Geometry/Soldermask Bottom")
		(17 "Dwgs.User" user "User.Drawings")
		(19 "Cmts.User" user "User.Comments")
		(21 "Eco1.User" user "User.Eco1")
		(23 "Eco2.User" user "User.Eco2")
		(25 "Edge.Cuts" user "Board Geometry/Outline")
		(27 "Margin" user)
		(31 "F.CrtYd" user "Package Geometry/Place Bound Top")
		(29 "B.CrtYd" user "Package Geometry/Place Bound Bottom")
		(35 "F.Fab" user "Ref Des/Assembly Top")
		(33 "B.Fab" user "Ref Des/Assembly Bottom")
	)
	(footprint ""
		(layer "B.Cu")
		(at 166.66718 -145.97126 180)
		(property "Reference" "C6W13"
			(at -1.47828 0.78994 270)
			(unlocked yes)
			(layer "B.SilkS")
			(effects
				(font
					(size 0.4064 0.254)
					(thickness 0.1524)
				)
				(justify mirror)
			)
		)
		(property "Value" ""
			(at 0 0 0)
			(layer "B.Fab")
			(effects
				(font
					(size 1.27 1.27)
				)
				(justify mirror)
			)
		)
		(duplicate_pad_numbers_are_jumpers no)
		(fp_poly
			(pts
				(xy 0.7239 -0.2159) (xy -0.7239 -0.2159) (xy -0.7239 1.9939) (xy 0.7239 1.9939)
			)
			(stroke
				(width 0)
				(type default)
			)
			(fill no)
			(layer "B.CrtYd")
		)
		(fp_line
			(start 0.7239 1.9939)
			(end -0.7239 1.9939)
			(stroke
				(width 0.1)
				(type default)
			)
			(layer "B.Fab")
		)
		(fp_line
			(start 0.7239 -0.2159)
			(end 0.7239 1.9939)
			(stroke
				(width 0.1)
				(type default)
			)
			(layer "B.Fab")
		)
		(fp_line
			(start -0.7239 1.9939)
			(end -0.7239 -0.2159)
			(stroke
				(width 0.1)
				(type default)
			)
			(layer "B.Fab")
		)
		(fp_line
			(start -0.7239 -0.2159)
			(end 0.7239 -0.2159)
			(stroke
				(width 0.1)
				(type default)
			)
			(layer "B.Fab")
		)
		(pad "1" smd rect
			(at 0 0)
			(size 1.27 1.016)
			(layers "B.Cu" "B.Mask" "B.Paste")
			(net "PVTT_KLM")
		)
		(pad "2" smd rect
			(at 0 1.778)
			(size 1.27 1.016)
			(layers "B.Cu" "B.Mask" "B.Paste")
			(net "GND")
		)
		(zone
			(layer "B.Cu")
			(hatch none 0.5)
			(connect_pads
				(clearance 0)
			)
			(min_thickness 0.25)
			(keepout
				(tracks not_allowed)
				(vias allowed)
				(pads allowed)
				(copperpour not_allowed)
				(footprints allowed)
			)
			(placement
				(enabled no)
				(sheetname "")
			)
			(fill
				(thermal_gap 0.5)
				(thermal_bridge_width 0.5)
				(island_removal_mode 0)
			)
			(polygon
				(pts
					(xy 166.03218 -146.47926) (xy 167.30218 -146.47926) (xy 167.30218 -147.24126) (xy 166.03218 -147.24126)
				)
			)
		)
	)
	(footprint ""
		(layer "B.Cu")
		(at 396.113 -87.3125 180)
		(property "Reference" "R2N32"
			(at 0.8382 -0.67818 180)
			(unlocked yes)
			(layer "B.SilkS")
			(effects
				(font
					(size 0.4064 0.254)
					(thickness 0.1524)
				)
				(justify left mirror)
			)
		)
		(property "Value" ""
			(at 0 0 0)
			(layer "B.Fab")
			(effects
				(font
					(size 1.27 1.27)
				)
				(justify mirror)
			)
		)
		(duplicate_pad_numbers_are_jumpers no)
		(fp_poly
			(pts
				(xy 0.2794 -0.1016) (xy -0.2794 -0.1016) (xy -0.2794 0.9906) (xy 0.2794 0.9906)
			)
			(stroke
				(width 0)
				(type default)
			)
			(fill no)
			(layer "B.CrtYd")
		)
		(fp_line
			(start 0.2794 0.9906)
			(end -0.2794 0.9906)
			(stroke
				(width 0.1)
				(type default)
			)
			(layer "B.Fab")
		)
		(fp_line
			(start 0.2794 -0.1016)
			(end 0.2794 0.9906)
			(stroke
				(width 0.1)
				(type default)
			)
			(layer "B.Fab")
		)
		(fp_line
			(start -0.2794 0.9906)
			(end -0.2794 -0.1016)
			(stroke
				(width 0.1)
				(type default)
			)
			(layer "B.Fab")
		)
		(fp_line
			(start -0.2794 -0.1016)
			(end 0.2794 -0.1016)
			(stroke
				(width 0.1)
				(type default)
			)
			(layer "B.Fab")
		)
		(pad "1" smd rect
			(at 0 0)
			(size 0.508 0.508)
			(layers "B.Cu" "B.Mask" "B.Paste")
			(net "P3V3_STBY")
		)
		(pad "2" smd rect
			(at 0 0.889)
			(size 0.508 0.508)
			(layers "B.Cu" "B.Mask" "B.Paste")
			(net "FM_BIOS_SMI_ACTIVE_N")
		)
		(zone
			(layer "B.Cu")
			(hatch none 0.5)
			(connect_pads
				(clearance 0)
			)
			(min_thickness 0.25)
			(keepout
				(tracks not_allowed)
				(vias allowed)
				(pads allowed)
				(copperpour not_allowed)
				(footprints allowed)
			)
			(placement
				(enabled no)
				(sheetname "")
			)
			(fill
				(thermal_gap 0.5)
				(thermal_bridge_width 0.5)
				(island_removal_mode 0)
			)
			(polygon
				(pts
					(xy 395.859 -87.9475) (xy 396.367 -87.9475) (xy 396.367 -87.5665) (xy 395.859 -87.5665)
				)
			)
		)
		(zone
			(layer "B.Cu")
			(hatch none 0.5)
			(connect_pads
				(clearance 0)
			)
			(min_thickness 0.25)
			(keepout
				(tracks allowed)
				(vias not_allowed)
				(pads allowed)
				(copperpour not_allowed)
				(footprints allowed)
			)
			(placement
				(enabled no)
				(sheetname "")
			)
			(fill
				(thermal_gap 0.5)
				(thermal_bridge_width 0.5)
				(island_removal_mode 0)
			)
			(polygon
				(pts
					(xy 395.859 -87.5665) (xy 396.367 -87.5665) (xy 396.367 -87.9475) (xy 395.859 -87.9475)
				)
			)
		)
	)
	(footprint ""
		(layer "B.Cu")
		(at 104.5591 -145.0086 90)
		(property "Reference" "C8L5"
			(at -1.848866 0.752348 90)
			(unlocked yes)
			(layer "B.SilkS")
			(effects
				(font
					(size 1.27 0.9652)
					(thickness 0.1524)
				)
				(justify mirror)
			)
		)
		(property "Value" ""
			(at 0 0 90)
			(layer "B.Fab")
			(effects
				(font
					(size 1.27 1.27)
				)
				(justify mirror)
			)
		)
		(duplicate_pad_numbers_are_jumpers no)
		(fp_rect
			(start 0.500126 1.598422)
			(end -0.500126 -0.201422)
			(stroke
				(width 0)
				(type default)
			)
			(fill no)
			(layer "B.CrtYd")
		)
		(fp_line
			(start 0.500126 -0.201422)
			(end -0.500126 -0.201422)
			(stroke
				(width 0.1)
				(type default)
			)
			(layer "B.Fab")
		)
		(fp_line
			(start -0.500126 -0.201422)
			(end -0.500126 1.598422)
			(stroke
				(width 0.1)
				(type default)
			)
			(layer "B.Fab")
		)
		(fp_line
			(start 0.500126 1.598422)
			(end 0.500126 -0.201422)
			(stroke
				(width 0.1)
				(type default)
			)
			(layer "B.Fab")
		)
		(fp_line
			(start -0.500126 1.598422)
			(end 0.500126 1.598422)
			(stroke
				(width 0.1)
				(type default)
			)
			(layer "B.Fab")
		)
		(pad "1" smd rect
			(at 0 0)
			(size 0.889 0.9906)
			(layers "B.Cu" "B.Mask" "B.Paste")
			(net "PVDDQ_KLM")
		)
		(pad "2" smd rect
			(at 0 1.397)
			(size 0.889 0.9906)
			(layers "B.Cu" "B.Mask" "B.Paste")
			(net "GND")
		)
		(zone
			(layer "B.Cu")
			(hatch none 0.5)
			(connect_pads
				(clearance 0)
			)
			(min_thickness 0.25)
			(keepout
				(tracks allowed)
				(vias not_allowed)
				(pads allowed)
				(copperpour not_allowed)
				(footprints allowed)
			)
			(placement
				(enabled no)
				(sheetname "")
			)
			(fill
				(thermal_gap 0.5)
				(thermal_bridge_width 0.5)
				(island_removal_mode 0)
			)
			(polygon
				(pts
					(xy 105.5116 -145.5039) (xy 105.0036 -145.5039) (xy 105.0036 -144.5133) (xy 105.5116 -144.5133)
				)
			)
		)
		(zone
			(layer "B.Cu")
			(hatch none 0.5)
			(connect_pads
				(clearance 0)
			)
			(min_thickness 0.25)
			(keepout
				(tracks not_allowed)
				(vias allowed)
				(pads allowed)
				(copperpour not_allowed)
				(footprints allowed)
			)
			(placement
				(enabled no)
				(sheetname "")
			)
			(fill
				(thermal_gap 0.5)
				(thermal_bridge_width 0.5)
				(island_removal_mode 0)
			)
			(polygon
				(pts
					(xy 105.5116 -145.5039) (xy 105.0036 -145.5039) (xy 105.0036 -144.5133) (xy 105.5116 -144.5133)
				)
			)
		)
	)
)
